(kicad_pcb
	(version 20260206)
	(generator "pcbnew")
	(generator_version "10.0")
	(general
		(thickness 1.6)
		(legacy_teardrops no)
	)
	(paper "A4")
	(title_block
		(title "dpb — 14545-sa.0730WZS0815.brd")
		(comment 1 "Honey Badger (Wiwynn) / footprints 971-977 of 1066")
	)
	(layers
		(0 "F.Cu" signal "TOP")
		(4 "In1.Cu" signal "L2GND")
		(6 "In2.Cu" signal "L3")
		(8 "In3.Cu" signal "L4VCC")
		(10 "In4.Cu" signal "L5VCC")
		(12 "In5.Cu" signal "L6")
		(14 "In6.Cu" signal "L7GND")
		(2 "B.Cu" signal "BOTTOM")
		(9 "F.Adhes" user "F.Adhesive")
		(11 "B.Adhes" user "B.Adhesive")
		(13 "F.Paste" user "Package Geometry/Pastemask Top")
		(15 "B.Paste" user "Package Geometry/Pastemask Bottom")
		(5 "F.SilkS" user "Ref Des/Silkscreen Top")
		(7 "B.SilkS" user "Ref Des/Silkscreen Bottom")
		(1 "F.Mask" user "Board Geometry/Soldermask Top")
		(3 "B.Mask" user "Board Geometry/Soldermask Bottom")
		(17 "Dwgs.User" user "User.Drawings")
		(19 "Cmts.User" user "User.Comments")
		(21 "Eco1.User" user "User.Eco1")
		(23 "Eco2.User" user "User.Eco2")
		(25 "Edge.Cuts" user "Board Geometry/Outline")
		(27 "Margin" user)
		(31 "F.CrtYd" user "Package Geometry/Place Bound Top")
		(29 "B.CrtYd" user "Package Geometry/Place Bound Bottom")
		(35 "F.Fab" user "Ref Des/Assembly Top")
		(33 "B.Fab" user "Ref Des/Assembly Bottom")
	)
	(footprint ""
		(layer "F.Cu")
		(at 219.175584 -188.869828 180)
		(property "Reference" "C163"
			(at 0 0 180)
			(layer "F.SilkS")
			(hide yes)
			(effects
				(font
					(size 1.27 1.27)
				)
			)
		)
		(property "Value" "SC1U25V3KX-1-GP"
			(at 0 -2.8194 180)
			(unlocked yes)
			(layer "F.Fab")
			(hide yes)
			(effects
				(font
					(size 1.016 1.016)
					(thickness 0.1524)
				)
			)
		)
		(property "Device Type" "C603H36"
			(at 0 -4.3434 180)
			(unlocked yes)
			(layer "F.Fab")
			(hide yes)
			(effects
				(font
					(size 1.016 1.016)
					(thickness 0.1524)
				)
			)
		)
		(duplicate_pad_numbers_are_jumpers no)
		(fp_line
			(start 0.508 0)
			(end -0.508 0)
			(stroke
				(width 0.2032)
				(type default)
			)
			(layer "F.SilkS")
		)
		(fp_rect
			(start -0.5842 1.3335)
			(end 0.5842 -1.3335)
			(stroke
				(width 0)
				(type default)
			)
			(fill no)
			(layer "F.CrtYd")
		)
		(fp_rect
			(start -0.5842 1.3335)
			(end 0.5842 -1.3335)
			(stroke
				(width 0)
				(type default)
			)
			(fill no)
			(layer "F.Fab")
		)
		(pad "1" smd custom
			(at 0 -0.762 180)
			(size 0.2159 0.2159)
			(layers "F.Cu" "F.Mask" "F.Paste")
			(net "P12V_HDD3")
			(options
				(clearance outline)
				(anchor circle)
			)
			(primitives
				(gr_poly
					(pts
						(arc
							(start -0.3302 -0.4318)
							(mid -0.402042 -0.402042)
							(end -0.4318 -0.3302)
						)
						(arc
							(start -0.4318 0.3302)
							(mid -0.402042 0.402042)
							(end -0.3302 0.4318)
						)
						(arc
							(start 0.3302 0.4318)
							(mid 0.402042 0.402042)
							(end 0.4318 0.3302)
						)
						(arc
							(start 0.4318 -0.3302)
							(mid 0.402042 -0.402042)
							(end 0.3302 -0.4318)
						)
					)
					(width 0)
					(fill yes)
				)
			)
		)
		(pad "2" smd custom
			(at 0 0.762 180)
			(size 0.2159 0.2159)
			(layers "F.Cu" "F.Mask" "F.Paste")
			(net "GND")
			(options
				(clearance outline)
				(anchor circle)
			)
			(primitives
				(gr_poly
					(pts
						(arc
							(start -0.3302 -0.4318)
							(mid -0.402042 -0.402042)
							(end -0.4318 -0.3302)
						)
						(arc
							(start -0.4318 0.3302)
							(mid -0.402042 0.402042)
							(end -0.3302 0.4318)
						)
						(arc
							(start 0.3302 0.4318)
							(mid 0.402042 0.402042)
							(end 0.4318 0.3302)
						)
						(arc
							(start 0.4318 -0.3302)
							(mid 0.402042 -0.402042)
							(end 0.3302 -0.4318)
						)
					)
					(width 0)
					(fill yes)
				)
			)
		)
	)
	(footprint ""
		(layer "F.Cu")
		(at 56.260492 -72.164956)
		(property "Reference" "R237"
			(at 0 0 0)
			(layer "F.SilkS")
			(hide yes)
			(effects
				(font
					(size 1.27 1.27)
				)
			)
		)
		(property "Value" "220R3F-1-GP"
			(at -0.0254 -2.5146 0)
			(unlocked yes)
			(layer "F.Fab")
			(hide yes)
			(effects
				(font
					(size 1.016 1.016)
					(thickness 0.1524)
				)
			)
		)
		(property "Device Type" "R603H22"
			(at -0.0254 -4.0386 0)
			(unlocked yes)
			(layer "F.Fab")
			(hide yes)
			(effects
				(font
					(size 1.016 1.016)
					(thickness 0.1524)
				)
			)
		)
		(duplicate_pad_numbers_are_jumpers no)
		(fp_line
			(start -0.4826 0)
			(end -0.2032 0)
			(stroke
				(width 0.2032)
				(type default)
			)
			(layer "F.SilkS")
		)
		(fp_line
			(start 0.2032 0)
			(end 0.4826 0)
			(stroke
				(width 0.2032)
				(type default)
			)
			(layer "F.SilkS")
		)
		(fp_rect
			(start -0.5842 1.3335)
			(end 0.5842 -1.3335)
			(stroke
				(width 0)
				(type default)
			)
			(fill no)
			(layer "F.CrtYd")
		)
		(fp_rect
			(start -0.5842 1.3335)
			(end 0.5842 -1.3335)
			(stroke
				(width 0)
				(type default)
			)
			(fill no)
			(layer "F.Fab")
		)
		(pad "1" smd custom
			(at 0 -0.762)
			(size 0.2159 0.2159)
			(layers "F.Cu" "F.Mask" "F.Paste")
			(net "HDD_PRSNT_NET9")
			(options
				(clearance outline)
				(anchor circle)
			)
			(primitives
				(gr_poly
					(pts
						(arc
							(start -0.3302 -0.4318)
							(mid -0.402042 -0.402042)
							(end -0.4318 -0.3302)
						)
						(arc
							(start -0.4318 0.3302)
							(mid -0.402042 0.402042)
							(end -0.3302 0.4318)
						)
						(arc
							(start 0.3302 0.4318)
							(mid 0.402042 0.402042)
							(end 0.4318 0.3302)
						)
						(arc
							(start 0.4318 -0.3302)
							(mid 0.402042 -0.402042)
							(end 0.3302 -0.4318)
						)
					)
					(width 0)
					(fill yes)
				)
			)
		)
		(pad "2" smd custom
			(at 0 0.762)
			(size 0.2159 0.2159)
			(layers "F.Cu" "F.Mask" "F.Paste")
			(net "HDD_PRSNT9")
			(options
				(clearance outline)
				(anchor circle)
			)
			(primitives
				(gr_poly
					(pts
						(arc
							(start -0.3302 -0.4318)
							(mid -0.402042 -0.402042)
							(end -0.4318 -0.3302)
						)
						(arc
							(start -0.4318 0.3302)
							(mid -0.402042 0.402042)
							(end -0.3302 0.4318)
						)
						(arc
							(start 0.3302 0.4318)
							(mid 0.402042 0.402042)
							(end 0.4318 0.3302)
						)
						(arc
							(start 0.4318 -0.3302)
							(mid 0.402042 -0.402042)
							(end 0.3302 -0.4318)
						)
					)
					(width 0)
					(fill yes)
				)
			)
		)
	)
	(footprint ""
		(layer "F.Cu")
		(at 202.564746 -288.8107 -90)
		(property "Reference" "R431"
			(at 0 0 270)
			(layer "F.SilkS")
			(hide yes)
			(effects
				(font
					(size 1.27 1.27)
				)
			)
		)
		(property "Value" "4K7R2J-2-GP"
			(at 0.064008 -3.993896 270)
			(unlocked yes)
			(layer "F.Fab")
			(hide yes)
			(effects
				(font
					(size 1.016 1.016)
					(thickness 0.1524)
				)
			)
		)
		(property "Device Type" "R402H16"
			(at 0.064008 -5.517896 270)
			(unlocked yes)
			(layer "F.Fab")
			(hide yes)
			(effects
				(font
					(size 1.016 1.016)
					(thickness 0.1524)
				)
			)
		)
		(duplicate_pad_numbers_are_jumpers no)
		(fp_line
			(start -0.508 -0.9398)
			(end -0.508 0.9398)
			(stroke
				(width 0.1524)
				(type default)
			)
			(layer "F.SilkS")
		)
		(fp_line
			(start 0.508 -0.9398)
			(end -0.508 -0.9398)
			(stroke
				(width 0.1524)
				(type default)
			)
			(layer "F.SilkS")
		)
		(fp_rect
			(start -0.508 0.9398)
			(end 0.508 -0.9398)
			(stroke
				(width 0)
				(type default)
			)
			(fill no)
			(layer "F.CrtYd")
		)
		(fp_rect
			(start -0.508 0.9398)
			(end 0.508 -0.9398)
			(stroke
				(width 0)
				(type default)
			)
			(fill no)
			(layer "F.Fab")
		)
		(pad "1" smd custom
			(at 0 -0.4445 270)
			(size 0.1397 0.1397)
			(layers "F.Cu" "F.Mask" "F.Paste")
			(net "P3V3")
			(options
				(clearance outline)
				(anchor circle)
			)
			(primitives
				(gr_poly
					(pts
						(arc
							(start -0.1778 -0.2794)
							(mid -0.249642 -0.249642)
							(end -0.2794 -0.1778)
						)
						(arc
							(start -0.2794 0.1778)
							(mid -0.249642 0.249642)
							(end -0.1778 0.2794)
						)
						(arc
							(start 0.1778 0.2794)
							(mid 0.249642 0.249642)
							(end 0.2794 0.1778)
						)
						(arc
							(start 0.2794 -0.1778)
							(mid 0.249642 -0.249642)
							(end 0.1778 -0.2794)
						)
					)
					(width 0)
					(fill yes)
				)
			)
		)
		(pad "2" smd custom
			(at 0 0.4445 270)
			(size 0.1397 0.1397)
			(layers "F.Cu" "F.Mask" "F.Paste")
			(net "SAS2X28_A_HDD2_FLT")
			(options
				(clearance outline)
				(anchor circle)
			)
			(primitives
				(gr_poly
					(pts
						(arc
							(start -0.1778 -0.2794)
							(mid -0.249642 -0.249642)
							(end -0.2794 -0.1778)
						)
						(arc
							(start -0.2794 0.1778)
							(mid -0.249642 0.249642)
							(end -0.1778 0.2794)
						)
						(arc
							(start 0.1778 0.2794)
							(mid 0.249642 0.249642)
							(end 0.2794 0.1778)
						)
						(arc
							(start 0.2794 -0.1778)
							(mid 0.249642 -0.249642)
							(end 0.1778 -0.2794)
						)
					)
					(width 0)
					(fill yes)
				)
			)
		)
	)
	(footprint ""
		(layer "F.Cu")
		(at 221.360746 -346.3417 -90)
		(property "Reference" "R116"
			(at 0 0 270)
			(layer "F.SilkS")
			(hide yes)
			(effects
				(font
					(size 1.27 1.27)
				)
			)
		)
		(property "Value" "0R2J-2-GP"
			(at 0.064008 -3.993896 270)
			(unlocked yes)
			(layer "F.Fab")
			(hide yes)
			(effects
				(font
					(size 1.016 1.016)
					(thickness 0.1524)
				)
			)
		)
		(property "Device Type" "R402H16"
			(at 0.064008 -5.517896 270)
			(unlocked yes)
			(layer "F.Fab")
			(hide yes)
			(effects
				(font
					(size 1.016 1.016)
					(thickness 0.1524)
				)
			)
		)
		(duplicate_pad_numbers_are_jumpers no)
		(fp_line
			(start -0.508 -0.9398)
			(end -0.508 0.9398)
			(stroke
				(width 0.1524)
				(type default)
			)
			(layer "F.SilkS")
		)
		(fp_line
			(start 0.508 -0.9398)
			(end -0.508 -0.9398)
			(stroke
				(width 0.1524)
				(type default)
			)
			(layer "F.SilkS")
		)
		(fp_rect
			(start -0.508 0.9398)
			(end 0.508 -0.9398)
			(stroke
				(width 0)
				(type default)
			)
			(fill no)
			(layer "F.CrtYd")
		)
		(fp_rect
			(start -0.508 0.9398)
			(end 0.508 -0.9398)
			(stroke
				(width 0)
				(type default)
			)
			(fill no)
			(layer "F.Fab")
		)
		(pad "1" smd custom
			(at 0 -0.4445 270)
			(size 0.1397 0.1397)
			(layers "F.Cu" "F.Mask" "F.Paste")
			(net "DRV_ACT_NET1")
			(options
				(clearance outline)
				(anchor circle)
			)
			(primitives
				(gr_poly
					(pts
						(arc
							(start -0.1778 -0.2794)
							(mid -0.249642 -0.249642)
							(end -0.2794 -0.1778)
						)
						(arc
							(start -0.2794 0.1778)
							(mid -0.249642 0.249642)
							(end -0.1778 0.2794)
						)
						(arc
							(start 0.1778 0.2794)
							(mid 0.249642 0.249642)
							(end 0.2794 0.1778)
						)
						(arc
							(start 0.2794 -0.1778)
							(mid 0.249642 -0.249642)
							(end 0.1778 -0.2794)
						)
					)
					(width 0)
					(fill yes)
				)
			)
		)
		(pad "2" smd custom
			(at 0 0.4445 270)
			(size 0.1397 0.1397)
			(layers "F.Cu" "F.Mask" "F.Paste")
			(net "DRIVE_ACT_1")
			(options
				(clearance outline)
				(anchor circle)
			)
			(primitives
				(gr_poly
					(pts
						(arc
							(start -0.1778 -0.2794)
							(mid -0.249642 -0.249642)
							(end -0.2794 -0.1778)
						)
						(arc
							(start -0.2794 0.1778)
							(mid -0.249642 0.249642)
							(end -0.1778 0.2794)
						)
						(arc
							(start 0.1778 0.2794)
							(mid 0.249642 0.249642)
							(end 0.2794 0.1778)
						)
						(arc
							(start 0.2794 -0.1778)
							(mid 0.249642 -0.249642)
							(end 0.1778 -0.2794)
						)
					)
					(width 0)
					(fill yes)
				)
			)
		)
	)
	(footprint ""
		(layer "F.Cu")
		(at 226.9236 -435.9148 -90)
		(property "Reference" "PR54"
			(at 0 0 270)
			(layer "F.SilkS")
			(hide yes)
			(effects
				(font
					(size 1.27 1.27)
				)
			)
		)
		(property "Value" "0R3J-0-U-GP"
			(at -0.0254 -2.5146 270)
			(unlocked yes)
			(layer "F.Fab")
			(hide yes)
			(effects
				(font
					(size 1.016 1.016)
					(thickness 0.1524)
				)
			)
		)
		(property "Device Type" "R603H22"
			(at -0.0254 -4.0386 270)
			(unlocked yes)
			(layer "F.Fab")
			(hide yes)
			(effects
				(font
					(size 1.016 1.016)
					(thickness 0.1524)
				)
			)
		)
		(duplicate_pad_numbers_are_jumpers no)
		(fp_line
			(start -0.4826 0)
			(end -0.2032 0)
			(stroke
				(width 0.2032)
				(type default)
			)
			(layer "F.SilkS")
		)
		(fp_line
			(start 0.2032 0)
			(end 0.4826 0)
			(stroke
				(width 0.2032)
				(type default)
			)
			(layer "F.SilkS")
		)
		(fp_rect
			(start -0.5842 1.3335)
			(end 0.5842 -1.3335)
			(stroke
				(width 0)
				(type default)
			)
			(fill no)
			(layer "F.CrtYd")
		)
		(fp_rect
			(start -0.5842 1.3335)
			(end 0.5842 -1.3335)
			(stroke
				(width 0)
				(type default)
			)
			(fill no)
			(layer "F.Fab")
		)
		(pad "1" smd custom
			(at 0 -0.762 270)
			(size 0.2159 0.2159)
			(layers "F.Cu" "F.Mask" "F.Paste")
			(net "P3V3_LX_COOPER")
			(options
				(clearance outline)
				(anchor circle)
			)
			(primitives
				(gr_poly
					(pts
						(arc
							(start -0.3302 -0.4318)
							(mid -0.402042 -0.402042)
							(end -0.4318 -0.3302)
						)
						(arc
							(start -0.4318 0.3302)
							(mid -0.402042 0.402042)
							(end -0.3302 0.4318)
						)
						(arc
							(start 0.3302 0.4318)
							(mid 0.402042 0.402042)
							(end 0.4318 0.3302)
						)
						(arc
							(start 0.4318 -0.3302)
							(mid 0.402042 -0.402042)
							(end 0.3302 -0.4318)
						)
					)
					(width 0)
					(fill yes)
				)
			)
		)
		(pad "2" smd custom
			(at 0 0.762 270)
			(size 0.2159 0.2159)
			(layers "F.Cu" "F.Mask" "F.Paste")
			(net "P3V3_FB_R")
			(options
				(clearance outline)
				(anchor circle)
			)
			(primitives
				(gr_poly
					(pts
						(arc
							(start -0.3302 -0.4318)
							(mid -0.402042 -0.402042)
							(end -0.4318 -0.3302)
						)
						(arc
							(start -0.4318 0.3302)
							(mid -0.402042 0.402042)
							(end -0.3302 0.4318)
						)
						(arc
							(start 0.3302 0.4318)
							(mid 0.402042 0.402042)
							(end 0.4318 0.3302)
						)
						(arc
							(start 0.4318 -0.3302)
							(mid 0.402042 -0.402042)
							(end 0.3302 -0.4318)
						)
					)
					(width 0)
					(fill yes)
				)
			)
		)
	)
	(footprint ""
		(layer "F.Cu")
		(at 32.384746 -311.432702)
		(property "Reference" "R263"
			(at 0 0 0)
			(layer "F.SilkS")
			(hide yes)
			(effects
				(font
					(size 1.27 1.27)
				)
			)
		)
		(property "Value" "200KR2F-L-GP"
			(at 0.064008 -3.993896 0)
			(unlocked yes)
			(layer "F.Fab")
			(hide yes)
			(effects
				(font
					(size 1.016 1.016)
					(thickness 0.1524)
				)
			)
		)
		(property "Device Type" "R402H16"
			(at 0.064008 -5.517896 0)
			(unlocked yes)
			(layer "F.Fab")
			(hide yes)
			(effects
				(font
					(size 1.016 1.016)
					(thickness 0.1524)
				)
			)
		)
		(duplicate_pad_numbers_are_jumpers no)
		(fp_line
			(start -0.508 -0.9398)
			(end -0.508 0.9398)
			(stroke
				(width 0.1524)
				(type default)
			)
			(layer "F.SilkS")
		)
		(fp_line
			(start 0.508 -0.9398)
			(end -0.508 -0.9398)
			(stroke
				(width 0.1524)
				(type default)
			)
			(layer "F.SilkS")
		)
		(fp_rect
			(start -0.508 0.9398)
			(end 0.508 -0.9398)
			(stroke
				(width 0)
				(type default)
			)
			(fill no)
			(layer "F.CrtYd")
		)
		(fp_rect
			(start -0.508 0.9398)
			(end 0.508 -0.9398)
			(stroke
				(width 0)
				(type default)
			)
			(fill no)
			(layer "F.Fab")
		)
		(pad "1" smd custom
			(at 0 -0.4445)
			(size 0.1397 0.1397)
			(layers "F.Cu" "F.Mask" "F.Paste")
			(net "P12V")
			(options
				(clearance outline)
				(anchor circle)
			)
			(primitives
				(gr_poly
					(pts
						(arc
							(start -0.1778 -0.2794)
							(mid -0.249642 -0.249642)
							(end -0.2794 -0.1778)
						)
						(arc
							(start -0.2794 0.1778)
							(mid -0.249642 0.249642)
							(end -0.1778 0.2794)
						)
						(arc
							(start 0.1778 0.2794)
							(mid 0.249642 0.249642)
							(end 0.2794 0.1778)
						)
						(arc
							(start 0.2794 -0.1778)
							(mid 0.249642 -0.249642)
							(end 0.1778 -0.2794)
						)
					)
					(width 0)
					(fill yes)
				)
			)
		)
		(pad "2" smd custom
			(at 0 0.4445)
			(size 0.1397 0.1397)
			(layers "F.Cu" "F.Mask" "F.Paste")
			(net "SW_HDD11_P")
			(options
				(clearance outline)
				(anchor circle)
			)
			(primitives
				(gr_poly
					(pts
						(arc
							(start -0.1778 -0.2794)
							(mid -0.249642 -0.249642)
							(end -0.2794 -0.1778)
						)
						(arc
							(start -0.2794 0.1778)
							(mid -0.249642 0.249642)
							(end -0.1778 0.2794)
						)
						(arc
							(start 0.1778 0.2794)
							(mid 0.249642 0.249642)
							(end 0.2794 0.1778)
						)
						(arc
							(start 0.2794 -0.1778)
							(mid 0.249642 -0.249642)
							(end 0.1778 -0.2794)
						)
					)
					(width 0)
					(fill yes)
				)
			)
		)
	)
	(footprint ""
		(layer "F.Cu")
		(at 80.898492 -85.499956 -90)
		(property "Reference" "U30"
			(at 0 0 270)
			(layer "F.SilkS")
			(hide yes)
			(effects
				(font
					(size 1.27 1.27)
				)
			)
		)
		(property "Value" "74LVC1G08GW-1-GP"
			(at -2.3368 -8.6868 270)
			(unlocked yes)
			(layer "F.Fab")
			(hide yes)
			(effects
				(font
					(size 1.016 1.016)
					(thickness 0.1524)
				)
			)
		)
		(property "Device Type" "SC70-5H44"
			(at -2.3114 -10.414 270)
			(unlocked yes)
			(layer "F.Fab")
			(hide yes)
			(effects
				(font
					(size 1.016 1.016)
					(thickness 0.1524)
				)
			)
		)
		(duplicate_pad_numbers_are_jumpers no)
		(fp_line
			(start -1.27 1.7018)
			(end -1.27 -1.7018)
			(stroke
				(width 0.1524)
				(type default)
			)
			(layer "F.SilkS")
		)
		(fp_line
			(start 1.27 1.7018)
			(end -1.27 1.7018)
			(stroke
				(width 0.1524)
				(type default)
			)
			(layer "F.SilkS")
		)
		(fp_line
			(start -1.27 -1.7018)
			(end 1.27 -1.7018)
			(stroke
				(width 0.1524)
				(type default)
			)
			(layer "F.SilkS")
		)
		(fp_line
			(start 1.27 -1.7018)
			(end 1.27 1.7018)
			(stroke
				(width 0.1524)
				(type default)
			)
			(layer "F.SilkS")
		)
		(fp_line
			(start 0.6604 -1.8034)
			(end 1.3843 -1.8034)
			(stroke
				(width 0.3302)
				(type default)
			)
			(layer "F.SilkS")
		)
		(fp_line
			(start 1.3843 -1.8034)
			(end 1.3843 -1.1176)
			(stroke
				(width 0.3302)
				(type default)
			)
			(layer "F.SilkS")
		)
		(fp_rect
			(start -1.524 1.9558)
			(end 1.524 -1.9558)
			(stroke
				(width 0)
				(type default)
			)
			(fill no)
			(layer "F.CrtYd")
		)
		(fp_poly
			(pts
				(xy -1.524 -1.9558) (xy 1.524 -1.9558) (xy 1.524 1.9558) (xy -1.524 1.9558)
			)
			(stroke
				(width 0)
				(type default)
			)
			(fill no)
			(layer "F.Fab")
		)
		(pad "1" smd rect
			(at 0.65024 -0.8255 270)
			(size 0.4064 1.2192)
			(layers "F.Cu" "F.Mask" "F.Paste")
			(net "SAS_EXP_B_PWR9")
		)
		(pad "2" smd rect
			(at 0 -0.8255 270)
			(size 0.4064 1.2192)
			(layers "F.Cu" "F.Mask" "F.Paste")
			(net "SAS_EXP_A_PWR9")
		)
		(pad "3" smd rect
			(at -0.65024 -0.8255 270)
			(size 0.4064 1.2192)
			(layers "F.Cu" "F.Mask" "F.Paste")
			(net "GND")
		)
		(pad "4" smd rect
			(at -0.65024 0.8255 270)
			(size 0.4064 1.2192)
			(layers "F.Cu" "F.Mask" "F.Paste")
			(net "DRIVE_PWR9")
		)
		(pad "5" smd rect
			(at 0.65024 0.8255 270)
			(size 0.4064 1.2192)
			(layers "F.Cu" "F.Mask" "F.Paste")
			(net "P3V3")
		)
	)
)
